# BASEBOARD_FAB2 (Tioga Pass) — schematic netlist excerpt (pin names and nets, part order shuffled) for the footprints in the layout excerpt that follows; sources: Cadence DE-HDL packaged netlist, KiCad conversion of Wiwynn_Tioga_Pass_MB.brd

R4E4  RES  1.00K 1% CHIP  pkg 0402  page 201 : A = P3V3_STBY ; B = FM_PVCCIN_CPU0_PWR_IN_ALERT_N
C1F9  CAP_A  0.01UF 25V 10% X7R  pkg 0402V  page 161 : A = FAN_TACH0 ; B = GND
CF2  SC22P50V2JN-4GP  5%  pkg SMD-BCG  page 201 : \1\ = VR_PVCCIN_CPU0_AIREF2 ; \2\ = ISENSE_PVCCIN_CPU0_PH2_IMON

(kicad_pcb
	(version 20260206)
	(generator "pcbnew")
	(generator_version "10.0")
	(general
		(thickness 1.6)
		(legacy_teardrops no)
	)
	(paper "A4")
	(title_block
		(title "Wiwynn_Tioga_Pass_MB.brd")
		(comment 1 "Tioga Pass / footprints 2264-2266 of 4770")
	)
	(layers
		(0 "F.Cu" signal "TOP")
		(4 "In1.Cu" signal "L2GND")
		(6 "In2.Cu" signal "L3")
		(8 "In3.Cu" signal "L4GND")
		(10 "In4.Cu" signal "L5")
		(12 "In5.Cu" signal "L6GND")
		(14 "In6.Cu" signal "L7VCC")
		(16 "In7.Cu" signal "L8VCC")
		(18 "In8.Cu" signal "L9GND")
		(20 "In9.Cu" signal "L10")
		(22 "In10.Cu" signal "L11GND")
		(24 "In11.Cu" signal "L12")
		(26 "In12.Cu" signal "L13GND")
		(2 "B.Cu" signal "BOTTOM")
		(9 "F.Adhes" user "F.Adhesive")
		(11 "B.Adhes" user "B.Adhesive")
		(13 "F.Paste" user "Package Geometry/Pastemask Top")
		(15 "B.Paste" user "Package Geometry/Pastemask Bottom")
		(5 "F.SilkS" user "Ref Des/Silkscreen Top")
		(7 "B.SilkS" user "Ref Des/Silkscreen Bottom")
		(1 "F.Mask" user "Board Geometry/Soldermask Top")
		(3 "B.Mask" user "Board Geometry/Soldermask Bottom")
		(17 "Dwgs.User" user "User.Drawings")
		(19 "Cmts.User" user "User.Comments")
		(21 "Eco1.User" user "User.Eco1")
		(23 "Eco2.User" user "User.Eco2")
		(25 "Edge.Cuts" user "Board Geometry/Outline")
		(27 "Margin" user)
		(31 "F.CrtYd" user "Package Geometry/Place Bound Top")
		(29 "B.CrtYd" user "Package Geometry/Place Bound Bottom")
		(35 "F.Fab" user "Ref Des/Assembly Top")
		(33 "B.Fab" user "Ref Des/Assembly Bottom")
	)
	(footprint ""
		(layer "F.Cu")
		(at 180.594 -64.135 180)
		(property "Reference" "R4E4"
			(at 0 0 180)
			(layer "F.SilkS")
			(hide yes)
			(effects
				(font
					(size 1.27 1.27)
				)
			)
		)
		(property "Value" ""
			(at 0 0 180)
			(layer "F.Fab")
			(effects
				(font
					(size 1.27 1.27)
				)
			)
		)
		(duplicate_pad_numbers_are_jumpers no)
		(fp_rect
			(start -0.2794 0.9906)
			(end 0.2794 -0.1016)
			(stroke
				(width 0)
				(type default)
			)
			(fill no)
			(layer "F.CrtYd")
		)
		(fp_line
			(start 0.2794 0.9906)
			(end 0.2794 -0.1016)
			(stroke
				(width 0.1)
				(type default)
			)
			(layer "F.Fab")
		)
		(fp_line
			(start 0.2794 -0.1016)
			(end -0.2794 -0.1016)
			(stroke
				(width 0.1)
				(type default)
			)
			(layer "F.Fab")
		)
		(fp_line
			(start -0.2794 0.9906)
			(end 0.2794 0.9906)
			(stroke
				(width 0.1)
				(type default)
			)
			(layer "F.Fab")
		)
		(fp_line
			(start -0.2794 -0.1016)
			(end -0.2794 0.9906)
			(stroke
				(width 0.1)
				(type default)
			)
			(layer "F.Fab")
		)
		(pad "1" smd rect
			(at 0 0 180)
			(size 0.508 0.508)
			(layers "F.Cu" "F.Mask" "F.Paste")
			(net "P3V3_STBY")
		)
		(pad "2" smd rect
			(at 0 0.889 180)
			(size 0.508 0.508)
			(layers "F.Cu" "F.Mask" "F.Paste")
			(net "FM_PVCCIN_CPU0_PWR_IN_ALERT_N")
		)
		(zone
			(layer "F.Cu")
			(hatch none 0.5)
			(connect_pads
				(clearance 0)
			)
			(min_thickness 0.25)
			(keepout
				(tracks allowed)
				(vias not_allowed)
				(pads allowed)
				(copperpour not_allowed)
				(footprints allowed)
			)
			(placement
				(enabled no)
				(sheetname "")
			)
			(fill
				(thermal_gap 0.5)
				(thermal_bridge_width 0.5)
				(island_removal_mode 0)
			)
			(polygon
				(pts
					(xy 180.848 -64.77) (xy 180.34 -64.77) (xy 180.34 -64.389) (xy 180.848 -64.389)
				)
			)
		)
		(zone
			(layer "F.Cu")
			(hatch none 0.5)
			(connect_pads
				(clearance 0)
			)
			(min_thickness 0.25)
			(keepout
				(tracks not_allowed)
				(vias allowed)
				(pads allowed)
				(copperpour not_allowed)
				(footprints allowed)
			)
			(placement
				(enabled no)
				(sheetname "")
			)
			(fill
				(thermal_gap 0.5)
				(thermal_bridge_width 0.5)
				(island_removal_mode 0)
			)
			(polygon
				(pts
					(xy 180.848 -64.77) (xy 180.34 -64.77) (xy 180.34 -64.389) (xy 180.848 -64.389)
				)
			)
		)
	)
	(footprint ""
		(layer "F.Cu")
		(at 26.489406 -31.738316 180)
		(property "Reference" "C1F9"
			(at 0 0 180)
			(layer "F.SilkS")
			(hide yes)
			(effects
				(font
					(size 1.27 1.27)
				)
			)
		)
		(property "Value" ""
			(at 0 0 180)
			(layer "F.Fab")
			(effects
				(font
					(size 1.27 1.27)
				)
			)
		)
		(duplicate_pad_numbers_are_jumpers no)
		(fp_rect
			(start 0.3048 -0.1016)
			(end -0.3048 0.9906)
			(stroke
				(width 0)
				(type default)
			)
			(fill no)
			(layer "F.CrtYd")
		)
		(fp_line
			(start 0.3048 0.9906)
			(end 0.3048 -0.1016)
			(stroke
				(width 0.1)
				(type default)
			)
			(layer "F.Fab")
		)
		(fp_line
			(start 0.3048 -0.1016)
			(end -0.3048 -0.1016)
			(stroke
				(width 0.1)
				(type default)
			)
			(layer "F.Fab")
		)
		(fp_line
			(start -0.3048 0.9906)
			(end 0.3048 0.9906)
			(stroke
				(width 0.1)
				(type default)
			)
			(layer "F.Fab")
		)
		(fp_line
			(start -0.3048 -0.1016)
			(end -0.3048 0.9906)
			(stroke
				(width 0.1)
				(type default)
			)
			(layer "F.Fab")
		)
		(pad "1" smd rect
			(at 0 0 180)
			(size 0.508 0.508)
			(layers "F.Cu" "F.Mask" "F.Paste")
			(net "FAN_TACH0")
		)
		(pad "2" smd rect
			(at 0 0.889 180)
			(size 0.508 0.508)
			(layers "F.Cu" "F.Mask" "F.Paste")
			(net "GND")
		)
		(zone
			(layer "F.Cu")
			(hatch none 0.5)
			(connect_pads
				(clearance 0)
			)
			(min_thickness 0.25)
			(keepout
				(tracks allowed)
				(vias not_allowed)
				(pads allowed)
				(copperpour not_allowed)
				(footprints allowed)
			)
			(placement
				(enabled no)
				(sheetname "")
			)
			(fill
				(thermal_gap 0.5)
				(thermal_bridge_width 0.5)
				(island_removal_mode 0)
			)
			(polygon
				(pts
					(xy 26.235406 -31.992316) (xy 26.743406 -31.992316) (xy 26.743406 -32.373316) (xy 26.235406 -32.373316)
				)
			)
		)
		(zone
			(layer "F.Cu")
			(hatch none 0.5)
			(connect_pads
				(clearance 0)
			)
			(min_thickness 0.25)
			(keepout
				(tracks not_allowed)
				(vias allowed)
				(pads allowed)
				(copperpour not_allowed)
				(footprints allowed)
			)
			(placement
				(enabled no)
				(sheetname "")
			)
			(fill
				(thermal_gap 0.5)
				(thermal_bridge_width 0.5)
				(island_removal_mode 0)
			)
			(polygon
				(pts
					(xy 26.235406 -31.992316) (xy 26.743406 -31.992316) (xy 26.743406 -32.373316) (xy 26.235406 -32.373316)
				)
			)
		)
	)
	(footprint ""
		(layer "F.Cu")
		(at 190.7286 -66.6242 180)
		(property "Reference" "CF2"
			(at 0 0 180)
			(layer "F.SilkS")
			(hide yes)
			(effects
				(font
					(size 1.27 1.27)
				)
			)
		)
		(property "Value" "*"
			(at 1.1811 -2.8194 180)
			(unlocked yes)
			(layer "F.Fab")
			(hide yes)
			(effects
				(font
					(size 1.27 1.016)
					(thickness 0.1524)
				)
			)
		)
		(property "Device Type" "SC22P50V2JN-4GP_SMD-BCG-SC22P5A"
			(at 1.1811 -4.3434 180)
			(unlocked yes)
			(layer "F.Fab")
			(hide yes)
			(effects
				(font
					(size 1.27 1.016)
					(thickness 0.1524)
				)
			)
		)
		(duplicate_pad_numbers_are_jumpers no)
		(fp_rect
			(start -0.4318 0.9525)
			(end 0.4318 -0.9525)
			(stroke
				(width 0)
				(type default)
			)
			(fill no)
			(layer "F.CrtYd")
		)
		(fp_rect
			(start -0.4318 0.9525)
			(end 0.4318 -0.9525)
			(stroke
				(width 0)
				(type default)
			)
			(fill no)
			(layer "F.Fab")
		)
		(pad "1" smd custom
			(at 0 -0.4445 180)
			(size 0.1524 0.1524)
			(layers "F.Cu" "F.Mask" "F.Paste")
			(net "VR_PVCCIN_CPU0_AIREF2")
			(options
				(clearance outline)
				(anchor circle)
			)
			(primitives
				(gr_poly
					(pts
						(arc
							(start 0.3048 -0.2032)
							(mid 0.275042 -0.275042)
							(end 0.2032 -0.3048)
						)
						(arc
							(start -0.2032 -0.3048)
							(mid -0.275042 -0.275042)
							(end -0.3048 -0.2032)
						)
						(arc
							(start -0.3048 0.2032)
							(mid -0.275042 0.275042)
							(end -0.2032 0.3048)
						)
						(arc
							(start 0.2032 0.3048)
							(mid 0.275042 0.275042)
							(end 0.3048 0.2032)
						)
					)
					(width 0)
					(fill yes)
				)
			)
		)
		(pad "2" smd custom
			(at 0 0.4445 180)
			(size 0.1524 0.1524)
			(layers "F.Cu" "F.Mask" "F.Paste")
			(net "ISENSE_PVCCIN_CPU0_PH2_IMON")
			(options
				(clearance outline)
				(anchor circle)
			)
			(primitives
				(gr_poly
					(pts
						(arc
							(start 0.3048 -0.2032)
							(mid 0.275042 -0.275042)
							(end 0.2032 -0.3048)
						)
						(arc
							(start -0.2032 -0.3048)
							(mid -0.275042 -0.275042)
							(end -0.3048 -0.2032)
						)
						(arc
							(start -0.3048 0.2032)
							(mid -0.275042 0.275042)
							(end -0.2032 0.3048)
						)
						(arc
							(start 0.2032 0.3048)
							(mid 0.275042 0.275042)
							(end 0.3048 0.2032)
						)
					)
					(width 0)
					(fill yes)
				)
			)
		)
	)
)
